# S9S_MB_2U (Grand Teton) — schematic netlist excerpt (pin names and nets, part order shuffled) for the footprints in the layout excerpt that follows; sources: Cadence DE-HDL packaged netlist, KiCad conversion of 03242023_DA0F0TMBIJ0_F0T_Motherboard_J_brd_V01_OCP.brd

PU17  ISL99390FRZTR5935  ISL99390FRZ-TR5935 IC  pkg QFN21_6X5XB  page 297
  VOS  = PVCCD_HV_CPU1_VOS
  AGND  = GND
  VCC  = PVCCD_HV_CPU1_VDD1
  PVCC  = PVCCFA_EHV_CPU1_PVCC
  PGND1  = GND
  GL1  = NC
  PGND2  = GND
  SW  = SW_PVCCD_HV_CPU1_SW1
  VIN1  = SW_P12V_PVCCINFAON_CPU1_FLT
  VIN2  = SW_P12V_PVCCINFAON_CPU1_FLT
  DNC  = NC
  PHASE  = SW_PVCCD_HV_CPU1_BOOTR1
  BOOT  = SW_PVCCD_HV_CPU1_BOOT1
  PWM  = PVCCD_HV_CPU1_APWM1
  EN  = PVCCD_HV_CPU1_VDD1
  TOUT_FLT  = PVCCD_HV_CPU1_ATSEN
  LSET  = PVCCD_HV_CPU1_LSET1
  IOUT  = PVCCD_HV_CPU1_ACSP1
  REFIN  = PVCCD_HV_CPU1_VREF
  PGND3  = GND
  GL2  = NC

(kicad_pcb
	(version 20260206)
	(generator "pcbnew")
	(generator_version "10.0")
	(general
		(thickness 1.6)
		(legacy_teardrops no)
	)
	(paper "A4")
	(title_block
		(title "03242023_DA0F0TMBIJ0_F0T_Motherboard_J_brd_V01_OCP.brd")
		(comment 1 "Grand Teton / footprints 1370-1370 of 6105")
	)
	(layers
		(0 "F.Cu" signal "TOP")
		(4 "In1.Cu" signal "GND")
		(6 "In2.Cu" signal "IN1")
		(8 "In3.Cu" signal "GND1")
		(10 "In4.Cu" signal "IN2")
		(12 "In5.Cu" signal "GND2")
		(14 "In6.Cu" signal "IN3")
		(16 "In7.Cu" signal "GND3")
		(18 "In8.Cu" signal "VCC")
		(20 "In9.Cu" signal "VCC1")
		(22 "In10.Cu" signal "GND4")
		(24 "In11.Cu" signal "IN4")
		(26 "In12.Cu" signal "GND5")
		(28 "In13.Cu" signal "IN5")
		(30 "In14.Cu" signal "GND6")
		(32 "In15.Cu" signal "IN6")
		(34 "In16.Cu" signal "GND7")
		(2 "B.Cu" signal "BOTTOM")
		(9 "F.Adhes" user "F.Adhesive")
		(11 "B.Adhes" user "B.Adhesive")
		(13 "F.Paste" user "Package Geometry/Pastemask Top")
		(15 "B.Paste" user "Package Geometry/Pastemask Bottom")
		(5 "F.SilkS" user "Ref Des/Silkscreen Top")
		(7 "B.SilkS" user "Ref Des/Silkscreen Bottom")
		(1 "F.Mask" user "Board Geometry/Soldermask Top")
		(3 "B.Mask" user "Board Geometry/Soldermask Bottom")
		(17 "Dwgs.User" user "User.Drawings")
		(19 "Cmts.User" user "User.Comments")
		(21 "Eco1.User" user "User.Eco1")
		(23 "Eco2.User" user "User.Eco2")
		(25 "Edge.Cuts" user "Board Geometry/Outline")
		(27 "Margin" user)
		(31 "F.CrtYd" user "Package Geometry/Place Bound Top")
		(29 "B.CrtYd" user "Package Geometry/Place Bound Bottom")
		(35 "F.Fab" user "Ref Des/Assembly Top")
		(33 "B.Fab" user "Ref Des/Assembly Bottom")
	)
	(footprint ""
		(layer "F.Cu")
		(at 54.89956 -165.11397 90)
		(property "Reference" "PU17"
			(at 1.74498 -9.2075 0)
			(unlocked yes)
			(layer "F.SilkS")
			(effects
				(font
					(size 0.7874 0.5842)
					(thickness 0.1524)
				)
				(justify left)
			)
		)
		(property "Value" ""
			(at 0 0 90)
			(layer "F.Fab")
			(effects
				(font
					(size 1.27 1.27)
				)
			)
		)
		(duplicate_pad_numbers_are_jumpers no)
		(fp_line
			(start 2.500122 -2.999994)
			(end 2.500122 -2.44348)
			(stroke
				(width 0.1524)
				(type default)
			)
			(layer "F.SilkS")
		)
		(fp_line
			(start 2.31394 -2.999994)
			(end 2.500122 -2.999994)
			(stroke
				(width 0.1524)
				(type default)
			)
			(layer "F.SilkS")
		)
		(fp_line
			(start -2.500122 -2.999994)
			(end -2.24409 -2.999994)
			(stroke
				(width 0.1524)
				(type default)
			)
			(layer "F.SilkS")
		)
		(fp_line
			(start -2.500122 -2.529078)
			(end -2.500122 -2.999994)
			(stroke
				(width 0.1524)
				(type default)
			)
			(layer "F.SilkS")
		)
		(fp_line
			(start -2.500122 0.6604)
			(end -2.500122 0.229108)
			(stroke
				(width 0.1524)
				(type default)
			)
			(layer "F.SilkS")
		)
		(fp_line
			(start 2.500122 2.339594)
			(end 2.500122 2.999994)
			(stroke
				(width 0.1524)
				(type default)
			)
			(layer "F.SilkS")
		)
		(fp_line
			(start 2.500122 2.999994)
			(end 2.2987 2.999994)
			(stroke
				(width 0.1524)
				(type default)
			)
			(layer "F.SilkS")
		)
		(fp_line
			(start -2.2987 2.999994)
			(end -2.500122 2.999994)
			(stroke
				(width 0.1524)
				(type default)
			)
			(layer "F.SilkS")
		)
		(fp_line
			(start -2.500122 2.999994)
			(end -2.500122 2.339594)
			(stroke
				(width 0.1524)
				(type default)
			)
			(layer "F.SilkS")
		)
		(fp_poly
			(pts
				(xy -5.130292 -2.813558) (xy -5.130292 -1.797558) (xy -4.114292 -2.305558)
			)
			(stroke
				(width 0)
				(type default)
			)
			(fill yes)
			(layer "F.SilkS")
		)
		(fp_line
			(start 2.500122 -2.999994)
			(end 2.500122 2.999994)
			(stroke
				(width 0.1)
				(type default)
			)
			(layer "F.Fab")
		)
		(fp_line
			(start -2.500122 -2.999994)
			(end 2.500122 -2.999994)
			(stroke
				(width 0.1)
				(type default)
			)
			(layer "F.Fab")
		)
		(fp_line
			(start 2.500122 2.999994)
			(end -2.500122 2.999994)
			(stroke
				(width 0.1)
				(type default)
			)
			(layer "F.Fab")
		)
		(fp_line
			(start -2.500122 2.999994)
			(end -2.500122 -2.999994)
			(stroke
				(width 0.1)
				(type default)
			)
			(layer "F.Fab")
		)
		(fp_poly
			(pts
				(xy -4.218432 -2.783078) (xy -4.218432 -1.767078) (xy -3.202432 -2.275078)
			)
			(stroke
				(width 0)
				(type default)
			)
			(fill yes)
			(layer "F.Fab")
		)
		(pad "1" smd rect
			(at -2.400046 -2.275078 180)
			(size 0.2286 0.6096)
			(layers "F.Cu" "F.Mask" "F.Paste")
			(net "PVCCD_HV_CPU1_VOS")
		)
		(pad "2" smd rect
			(at -2.400046 -1.82499 180)
			(size 0.2286 0.6096)
			(layers "F.Cu" "F.Mask" "F.Paste")
			(net "GND")
		)
		(pad "3" smd rect
			(at -2.400046 -1.374902 180)
			(size 0.2286 0.6096)
			(layers "F.Cu" "F.Mask" "F.Paste")
			(net "PVCCD_HV_CPU1_VDD1")
		)
		(pad "4" smd rect
			(at -2.400046 -0.925068 180)
			(size 0.2286 0.6096)
			(layers "F.Cu" "F.Mask" "F.Paste")
			(net "PVCCFA_EHV_CPU1_PVCC")
		)
		(pad "5" smd rect
			(at -2.400046 -0.47498 180)
			(size 0.2286 0.6096)
			(layers "F.Cu" "F.Mask" "F.Paste")
			(net "GND")
		)
		(pad "6" smd rect
			(at -2.400046 -0.024892 180)
			(size 0.2286 0.6096)
			(layers "F.Cu" "F.Mask" "F.Paste")
			(net "Net_1917")
		)
		(pad "7_9-20_24" smd circle
			(at 0 1.150112 180)
			(size 0 0)
			(layers "F.Cu" "F.Mask" "F.Paste")
			(net "GND")
		)
		(pad "10_19" smd rect
			(at 0 2.899918 180)
			(size 0.6096 4.318)
			(layers "F.Cu" "F.Mask" "F.Paste")
			(net "SW_PVCCD_HV_CPU1_SW1")
		)
		(pad "25_29" smd rect
			(at 1.549908 -1.279906)
			(size 2.0574 2.3114)
			(layers "F.Cu" "F.Mask" "F.Paste")
			(net "SW_P12V_PVCCINFAON_CPU1_FLT")
		)
		(pad "30" smd rect
			(at 2.05994 -2.899918 90)
			(size 0.2286 0.6096)
			(layers "F.Cu" "F.Mask" "F.Paste")
			(net "SW_P12V_PVCCINFAON_CPU1_FLT")
		)
		(pad "31" smd rect
			(at 1.610106 -2.899918 90)
			(size 0.2286 0.6096)
			(layers "F.Cu" "F.Mask" "F.Paste")
			(net "Net_1916")
		)
		(pad "32" smd rect
			(at 1.160018 -2.899918 90)
			(size 0.2286 0.6096)
			(layers "F.Cu" "F.Mask" "F.Paste")
			(net "SW_PVCCD_HV_CPU1_BOOTR1")
		)
		(pad "33" smd rect
			(at 0.70993 -2.899918 90)
			(size 0.2286 0.6096)
			(layers "F.Cu" "F.Mask" "F.Paste")
			(net "SW_PVCCD_HV_CPU1_BOOT1")
		)
		(pad "34" smd rect
			(at 0.260096 -2.899918 90)
			(size 0.2286 0.6096)
			(layers "F.Cu" "F.Mask" "F.Paste")
			(net "PVCCD_HV_CPU1_APWM1")
		)
		(pad "35" smd rect
			(at -0.189992 -2.899918 90)
			(size 0.2286 0.6096)
			(layers "F.Cu" "F.Mask" "F.Paste")
			(net "PVCCD_HV_CPU1_VDD1")
		)
		(pad "36" smd rect
			(at -0.64008 -2.899918 90)
			(size 0.2286 0.6096)
			(layers "F.Cu" "F.Mask" "F.Paste")
			(net "PVCCD_HV_CPU1_ATSEN")
		)
		(pad "37" smd rect
			(at -1.089914 -2.899918 90)
			(size 0.2286 0.6096)
			(layers "F.Cu" "F.Mask" "F.Paste")
			(net "PVCCD_HV_CPU1_LSET1")
		)
		(pad "38" smd rect
			(at -1.540002 -2.899918 90)
			(size 0.2286 0.6096)
			(layers "F.Cu" "F.Mask" "F.Paste")
			(net "PVCCD_HV_CPU1_ACSP1")
		)
		(pad "39" smd rect
			(at -1.99009 -2.899918 90)
			(size 0.2286 0.6096)
			(layers "F.Cu" "F.Mask" "F.Paste")
			(net "PVCCD_HV_CPU1_VREF")
		)
		(pad "40" smd rect
			(at -0.87503 -1.27508 90)
			(size 1.7526 1.9558)
			(layers "F.Cu" "F.Mask" "F.Paste")
			(net "GND")
		)
		(pad "41" smd rect
			(at -1.525016 0.249936)
			(size 0.3048 0.4572)
			(layers "F.Cu" "F.Mask" "F.Paste")
			(net "Net_1918")
		)
		(zone
			(layer "F.Cu")
			(hatch none 0.5)
			(connect_pads
				(clearance 0)
			)
			(min_thickness 0.25)
			(keepout
				(tracks not_allowed)
				(vias allowed)
				(pads allowed)
				(copperpour not_allowed)
				(footprints allowed)
			)
			(placement
				(enabled no)
				(sheetname "")
			)
			(fill
				(thermal_gap 0.5)
				(thermal_bridge_width 0.5)
				(island_removal_mode 0)
			)
			(polygon
				(pts
					(xy 57.899554 -162.613848) (xy 57.385966 -162.613848) (xy 57.150254 -162.84956) (xy 57.150254 -167.408606)
					(xy 57.35574 -167.614092) (xy 57.899554 -167.614092) (xy 57.899554 -167.32377) (xy 57.443878 -167.32377)
					(xy 57.443878 -162.90417) (xy 57.899554 -162.90417)
				)
			)
		)
	)
)
